(kicad_pcb
	(version 20260206)
	(generator "pcbnew")
	(generator_version "10.0")
	(general
		(thickness 1.6)
		(legacy_teardrops no)
	)
	(paper "A4")
	(title_block
		(title "Wiwynn_Tioga_Pass_MB.brd")
		(comment 1 "Tioga Pass / footprint 1664 of 4770 (U7C1), pads 1-114 of 1310")
	)
	(layers
		(0 "F.Cu" signal "TOP")
		(4 "In1.Cu" signal "L2GND")
		(6 "In2.Cu" signal "L3")
		(8 "In3.Cu" signal "L4GND")
		(10 "In4.Cu" signal "L5")
		(12 "In5.Cu" signal "L6GND")
		(14 "In6.Cu" signal "L7VCC")
		(16 "In7.Cu" signal "L8VCC")
		(18 "In8.Cu" signal "L9GND")
		(20 "In9.Cu" signal "L10")
		(22 "In10.Cu" signal "L11GND")
		(24 "In11.Cu" signal "L12")
		(26 "In12.Cu" signal "L13GND")
		(2 "B.Cu" signal "BOTTOM")
		(9 "F.Adhes" user "F.Adhesive")
		(11 "B.Adhes" user "B.Adhesive")
		(13 "F.Paste" user "Package Geometry/Pastemask Top")
		(15 "B.Paste" user "Package Geometry/Pastemask Bottom")
		(5 "F.SilkS" user "Ref Des/Silkscreen Top")
		(7 "B.SilkS" user "Ref Des/Silkscreen Bottom")
		(1 "F.Mask" user "Board Geometry/Soldermask Top")
		(3 "B.Mask" user "Board Geometry/Soldermask Bottom")
		(17 "Dwgs.User" user "User.Drawings")
		(19 "Cmts.User" user "User.Comments")
		(21 "Eco1.User" user "User.Eco1")
		(23 "Eco2.User" user "User.Eco2")
		(25 "Edge.Cuts" user "Board Geometry/Outline")
		(27 "Margin" user)
		(31 "F.CrtYd" user "Package Geometry/Place Bound Top")
		(29 "B.CrtYd" user "Package Geometry/Place Bound Bottom")
		(35 "F.Fab" user "Ref Des/Assembly Top")
		(33 "B.Fab" user "Ref Des/Assembly Bottom")
	)
	(footprint ""
		(layer "F.Cu")
		(at 387.985 -109.855 90)
		(property "Reference" "U7C1"
			(at 17.75333 -13.335 0)
			(unlocked yes)
			(layer "F.SilkS")
			(effects
				(font
					(size 0.7874 0.5842)
					(thickness 0.1524)
				)
				(justify left)
			)
		)
		(property "Value" ""
			(at 0 0 90)
			(layer "F.Fab")
			(effects
				(font
					(size 1.27 1.27)
				)
			)
		)
		(duplicate_pad_numbers_are_jumpers no)
		(pad "A5" smd circle
			(at -14.689328 -13.310108 90)
			(size 0.4064 0.4064)
			(layers "F.Cu" "F.Mask" "F.Paste")
			(net "GND")
		)
		(pad "A7" smd circle
			(at -13.876528 -13.310108 90)
			(size 0.4064 0.4064)
			(layers "F.Cu" "F.Mask" "F.Paste")
			(net "GND")
		)
		(pad "A9" smd circle
			(at -13.063728 -13.310108 90)
			(size 0.3556 0.3556)
			(layers "F.Cu" "F.Mask" "F.Paste")
			(net "GND")
		)
		(pad "A11" smd oval
			(at -11.999976 -13.310108 90)
			(size 0.254 0.3302)
			(layers "F.Cu" "F.Mask" "F.Paste")
			(net "TP_PCH_RSVD21")
		)
		(pad "A13" smd oval
			(at -10.999978 -13.310108 90)
			(size 0.254 0.3302)
			(layers "F.Cu" "F.Mask" "F.Paste")
			(net "FM_GBE_LOM_DISABLE_N")
		)
		(pad "A15" smd oval
			(at -9.99998 -13.310108 90)
			(size 0.254 0.3302)
			(layers "F.Cu" "F.Mask" "F.Paste")
			(net "FM_BMC_CPLD_MP_RST_N")
		)
		(pad "A18" smd oval
			(at -8.999982 -13.310108 90)
			(size 0.254 0.3302)
			(layers "F.Cu" "F.Mask" "F.Paste")
			(net "GND")
		)
		(pad "A20" smd oval
			(at -7.999984 -13.310108 90)
			(size 0.254 0.3302)
			(layers "F.Cu" "F.Mask" "F.Paste")
			(net "CLK_100M_SPRV_DP")
		)
		(pad "A22" smd oval
			(at -6.999986 -13.310108 90)
			(size 0.254 0.3302)
			(layers "F.Cu" "F.Mask" "F.Paste")
			(net "GND")
		)
		(pad "A24" smd oval
			(at -5.999988 -13.310108 90)
			(size 0.254 0.3302)
			(layers "F.Cu" "F.Mask" "F.Paste")
			(net "Net_4")
		)
		(pad "A26" smd oval
			(at -4.99999 -13.310108 90)
			(size 0.254 0.3302)
			(layers "F.Cu" "F.Mask" "F.Paste")
			(net "TP_PCH_RSVD65")
		)
		(pad "A28" smd oval
			(at -3.999992 -13.310108 90)
			(size 0.254 0.3302)
			(layers "F.Cu" "F.Mask" "F.Paste")
			(net "CLK_100M_PCH_SLOTX24_S2_DN")
		)
		(pad "A30" smd oval
			(at -2.999994 -13.310108 90)
			(size 0.254 0.3302)
			(layers "F.Cu" "F.Mask" "F.Paste")
			(net "GND")
		)
		(pad "A32" smd oval
			(at -1.999996 -13.310108 90)
			(size 0.254 0.3302)
			(layers "F.Cu" "F.Mask" "F.Paste")
			(net "TP_CLK_100M_NSSCC0_DN")
		)
		(pad "A34" smd oval
			(at -0.999998 -13.310108 90)
			(size 0.254 0.3302)
			(layers "F.Cu" "F.Mask" "F.Paste")
			(net "GND")
		)
		(pad "A37" smd oval
			(at 0 -13.310108 90)
			(size 0.254 0.3302)
			(layers "F.Cu" "F.Mask" "F.Paste")
			(net "GND")
		)
		(pad "A39" smd oval
			(at 0.999998 -13.310108 90)
			(size 0.254 0.3302)
			(layers "F.Cu" "F.Mask" "F.Paste")
			(net "CLK_100M_PCH_XDP_DN")
		)
		(pad "A41" smd oval
			(at 1.999996 -13.310108 90)
			(size 0.254 0.3302)
			(layers "F.Cu" "F.Mask" "F.Paste")
			(net "GND")
		)
		(pad "A43" smd oval
			(at 2.999994 -13.310108 90)
			(size 0.254 0.3302)
			(layers "F.Cu" "F.Mask" "F.Paste")
			(net "DMI_CPU0_PCH_TX_C_DP<1>")
		)
		(pad "A45" smd oval
			(at 3.999992 -13.310108 90)
			(size 0.254 0.3302)
			(layers "F.Cu" "F.Mask" "F.Paste")
			(net "DMI_CPU0_PCH_TX_C_DP<3>")
		)
		(pad "A48" smd oval
			(at 4.99999 -13.310108 90)
			(size 0.254 0.3302)
			(layers "F.Cu" "F.Mask" "F.Paste")
			(net "P3E_CPU0_PE1_PCH_TXP<0>")
		)
		(pad "A50" smd oval
			(at 5.999988 -13.310108 90)
			(size 0.254 0.3302)
			(layers "F.Cu" "F.Mask" "F.Paste")
			(net "P3E_CPU0_PE1_PCH_TXP<2>")
		)
		(pad "A52" smd oval
			(at 6.999986 -13.310108 90)
			(size 0.254 0.3302)
			(layers "F.Cu" "F.Mask" "F.Paste")
			(net "P3E_CPU0_PE1_PCH_TXP<4>")
		)
		(pad "A54" smd oval
			(at 7.999984 -13.310108 90)
			(size 0.254 0.3302)
			(layers "F.Cu" "F.Mask" "F.Paste")
			(net "P3E_CPU0_PE1_PCH_TXP<6>")
		)
		(pad "A57" smd oval
			(at 8.999982 -13.310108 90)
			(size 0.254 0.3302)
			(layers "F.Cu" "F.Mask" "F.Paste")
			(net "P3E_CPU0_PE1_PCH_C_TXN<8>")
		)
		(pad "A59" smd oval
			(at 9.99998 -13.310108 90)
			(size 0.254 0.3302)
			(layers "F.Cu" "F.Mask" "F.Paste")
			(net "P3E_CPU0_PE1_PCH_C_TXN<10>")
		)
		(pad "A61" smd oval
			(at 10.999978 -13.310108 90)
			(size 0.254 0.3302)
			(layers "F.Cu" "F.Mask" "F.Paste")
			(net "P3E_CPU0_PE1_PCH_C_TXN<12>")
		)
		(pad "A63" smd oval
			(at 11.999976 -13.310108 90)
			(size 0.254 0.3302)
			(layers "F.Cu" "F.Mask" "F.Paste")
			(net "P3E_CPU0_PE1_PCH_C_TXN<14>")
		)
		(pad "A65" smd circle
			(at 13.063728 -13.310108 90)
			(size 0.3556 0.3556)
			(layers "F.Cu" "F.Mask" "F.Paste")
			(net "GND")
		)
		(pad "A66" smd circle
			(at 13.876528 -13.310108 45)
			(size 0.4064 0.4064)
			(layers "F.Cu" "F.Mask" "F.Paste")
			(net "GND")
		)
		(pad "A68" smd circle
			(at 14.689328 -13.310108 45)
			(size 0.4064 0.4064)
			(layers "F.Cu" "F.Mask" "F.Paste")
			(net "GND")
		)
		(pad "A70" smd circle
			(at 15.502128 -13.310108 45)
			(size 0.5588 0.5588)
			(layers "F.Cu" "F.Mask" "F.Paste")
			(net "GND")
		)
		(pad "AA2" smd circle
			(at -15.895066 -4.500118 180)
			(size 0.3048 0.3048)
			(layers "F.Cu" "F.Mask" "F.Paste")
			(net "IRQ_PIRQA_SPI_TPM_N")
		)
		(pad "AA4" smd circle
			(at -15.064994 -4.500118 180)
			(size 0.3048 0.3048)
			(layers "F.Cu" "F.Mask" "F.Paste")
			(net "Net_482")
		)
		(pad "AA9" smd circle
			(at -12.8778 -4.21005)
			(size 0.381 0.381)
			(layers "F.Cu" "F.Mask" "F.Paste")
			(net "FM_CPU1_PROCHOT_PCH_N")
		)
		(pad "AA13" smd circle
			(at -11.16076 -4.21005)
			(size 0.381 0.381)
			(layers "F.Cu" "F.Mask" "F.Paste")
			(net "H_CPU1_MEMGHJ_MEMHOT_PCH_N")
		)
		(pad "AA17" smd circle
			(at -9.44372 -4.21005)
			(size 0.381 0.381)
			(layers "F.Cu" "F.Mask" "F.Paste")
			(net "FM_PRSNT_2_6_N")
		)
		(pad "AA20" smd circle
			(at -7.72668 -4.21005)
			(size 0.381 0.381)
			(layers "F.Cu" "F.Mask" "F.Paste")
			(net "FM_PRSNT_2_5_N")
		)
		(pad "AA24" smd circle
			(at -6.00964 -4.21005)
			(size 0.381 0.381)
			(layers "F.Cu" "F.Mask" "F.Paste")
			(net "P1V05_PCH_STBY")
		)
		(pad "AA26" smd circle
			(at -5.20065 -4.24815 180)
			(size 0.381 0.381)
			(layers "F.Cu" "F.Mask" "F.Paste")
			(net "GND")
		)
		(pad "AA27" smd circle
			(at -4.40055 -4.24815 180)
			(size 0.381 0.381)
			(layers "F.Cu" "F.Mask" "F.Paste")
			(net "GND")
		)
		(pad "AA29" smd circle
			(at -3.60045 -4.24815 180)
			(size 0.381 0.381)
			(layers "F.Cu" "F.Mask" "F.Paste")
			(net "PVNN_PCH_STBY")
		)
		(pad "AA30" smd circle
			(at -2.80035 -4.24815 180)
			(size 0.381 0.381)
			(layers "F.Cu" "F.Mask" "F.Paste")
			(net "PVNN_PCH_STBY")
		)
		(pad "AA32" smd circle
			(at -2.00025 -4.24815 180)
			(size 0.381 0.381)
			(layers "F.Cu" "F.Mask" "F.Paste")
			(net "PVNN_PCH_STBY")
		)
		(pad "AA34" smd circle
			(at -1.20015 -4.24815 180)
			(size 0.381 0.381)
			(layers "F.Cu" "F.Mask" "F.Paste")
			(net "PVNN_PCH_STBY")
		)
		(pad "AA36" smd circle
			(at -0.40005 -4.24815 180)
			(size 0.381 0.381)
			(layers "F.Cu" "F.Mask" "F.Paste")
			(net "PVNN_PCH_STBY")
		)
		(pad "AA37" smd circle
			(at 0.40005 -4.24815 180)
			(size 0.381 0.381)
			(layers "F.Cu" "F.Mask" "F.Paste")
			(net "PVNN_PCH_STBY")
		)
		(pad "AA39" smd circle
			(at 1.20015 -4.24815 180)
			(size 0.381 0.381)
			(layers "F.Cu" "F.Mask" "F.Paste")
			(net "PVNN_PCH_STBY")
		)
		(pad "AA41" smd circle
			(at 2.00025 -4.24815 180)
			(size 0.381 0.381)
			(layers "F.Cu" "F.Mask" "F.Paste")
			(net "PVNN_PCH_STBY")
		)
		(pad "AA43" smd circle
			(at 2.80035 -4.24815 180)
			(size 0.381 0.381)
			(layers "F.Cu" "F.Mask" "F.Paste")
			(net "GND")
		)
		(pad "AA45" smd circle
			(at 3.60045 -4.24815 180)
			(size 0.381 0.381)
			(layers "F.Cu" "F.Mask" "F.Paste")
			(net "P1V05_PCH_STBY")
		)
		(pad "AA46" smd circle
			(at 4.40055 -4.24815 180)
			(size 0.381 0.381)
			(layers "F.Cu" "F.Mask" "F.Paste")
			(net "P1V05_PCH_STBY")
		)
		(pad "AA48" smd circle
			(at 5.20065 -4.24815 180)
			(size 0.381 0.381)
			(layers "F.Cu" "F.Mask" "F.Paste")
			(net "GND")
		)
		(pad "AA50" smd circle
			(at 6.00964 -4.21005)
			(size 0.381 0.381)
			(layers "F.Cu" "F.Mask" "F.Paste")
			(net "GND")
		)
		(pad "AA54" smd circle
			(at 7.72668 -4.21005)
			(size 0.381 0.381)
			(layers "F.Cu" "F.Mask" "F.Paste")
			(net "TP_PCH_RSVD32")
		)
		(pad "AA58" smd circle
			(at 9.44372 -4.21005)
			(size 0.381 0.381)
			(layers "F.Cu" "F.Mask" "F.Paste")
			(net "TP_PCH_RSVD2")
		)
		(pad "AA61" smd circle
			(at 11.16076 -4.21005)
			(size 0.381 0.381)
			(layers "F.Cu" "F.Mask" "F.Paste")
			(net "SATA6G_PCH_PCIE_UP_SATA_RXN<7>")
		)
		(pad "AA65" smd circle
			(at 12.8778 -4.21005)
			(size 0.381 0.381)
			(layers "F.Cu" "F.Mask" "F.Paste")
			(net "P3E_CPU0_PE1_PCH_R_RXP<15>")
		)
		(pad "AA69" smd circle
			(at 15.064994 -4.500118)
			(size 0.3048 0.3048)
			(layers "F.Cu" "F.Mask" "F.Paste")
			(net "TP_PCH_RSVD51")
		)
		(pad "AA71" smd circle
			(at 15.895066 -4.500118)
			(size 0.3048 0.3048)
			(layers "F.Cu" "F.Mask" "F.Paste")
			(net "TP_PCH_RSVD52")
		)
		(pad "AB1" smd oval
			(at -16.310102 -3.999992 180)
			(size 0.254 0.3302)
			(layers "F.Cu" "F.Mask" "F.Paste")
			(net "PU_LPC_CLKRUN_N")
		)
		(pad "AB3" smd circle
			(at -15.48003 -3.999992 180)
			(size 0.3048 0.3048)
			(layers "F.Cu" "F.Mask" "F.Paste")
			(net "FM_MB_SLOT_ID1")
		)
		(pad "AB5" smd circle
			(at -14.649958 -3.999992 180)
			(size 0.3048 0.3048)
			(layers "F.Cu" "F.Mask" "F.Paste")
			(net "GND")
		)
		(pad "AB68" smd circle
			(at 14.649958 -3.999992)
			(size 0.3048 0.3048)
			(layers "F.Cu" "F.Mask" "F.Paste")
			(net "GND")
		)
		(pad "AB70" smd circle
			(at 15.48003 -3.999992)
			(size 0.3048 0.3048)
			(layers "F.Cu" "F.Mask" "F.Paste")
			(net "GND")
		)
		(pad "AB72" smd oval
			(at 16.310102 -3.999992 180)
			(size 0.254 0.3302)
			(layers "F.Cu" "F.Mask" "F.Paste")
			(net "GND")
		)
		(pad "AC2" smd circle
			(at -15.895066 -3.50012 180)
			(size 0.3048 0.3048)
			(layers "F.Cu" "F.Mask" "F.Paste")
			(net "PU_LPC_PME_N")
		)
		(pad "AC4" smd circle
			(at -15.064994 -3.50012 180)
			(size 0.3048 0.3048)
			(layers "F.Cu" "F.Mask" "F.Paste")
			(net "FM_MB_SLOT_ID2")
		)
		(pad "AC7" smd circle
			(at -13.73632 -3.71475)
			(size 0.381 0.381)
			(layers "F.Cu" "F.Mask" "F.Paste")
			(net "GND")
		)
		(pad "AC11" smd circle
			(at -12.01928 -3.71475)
			(size 0.381 0.381)
			(layers "F.Cu" "F.Mask" "F.Paste")
			(net "GND")
		)
		(pad "AC15" smd circle
			(at -10.30224 -3.71475)
			(size 0.381 0.381)
			(layers "F.Cu" "F.Mask" "F.Paste")
			(net "GND")
		)
		(pad "AC18" smd circle
			(at -8.5852 -3.71475)
			(size 0.381 0.381)
			(layers "F.Cu" "F.Mask" "F.Paste")
			(net "GND")
		)
		(pad "AC22" smd circle
			(at -6.86816 -3.71475)
			(size 0.381 0.381)
			(layers "F.Cu" "F.Mask" "F.Paste")
			(net "GND")
		)
		(pad "AC26" smd circle
			(at -5.20065 -3.44805 180)
			(size 0.381 0.381)
			(layers "F.Cu" "F.Mask" "F.Paste")
			(net "P1V05_PCH_STBY")
		)
		(pad "AC27" smd circle
			(at -4.40055 -3.44805 180)
			(size 0.381 0.381)
			(layers "F.Cu" "F.Mask" "F.Paste")
			(net "GND")
		)
		(pad "AC29" smd circle
			(at -3.60045 -3.44805 180)
			(size 0.381 0.381)
			(layers "F.Cu" "F.Mask" "F.Paste")
			(net "PVNN_PCH_STBY")
		)
		(pad "AC30" smd circle
			(at -2.80035 -3.44805 180)
			(size 0.381 0.381)
			(layers "F.Cu" "F.Mask" "F.Paste")
			(net "PVNN_PCH_STBY")
		)
		(pad "AC32" smd circle
			(at -2.00025 -3.44805 180)
			(size 0.381 0.381)
			(layers "F.Cu" "F.Mask" "F.Paste")
			(net "PVNN_PCH_STBY")
		)
		(pad "AC34" smd circle
			(at -1.20015 -3.44805 180)
			(size 0.381 0.381)
			(layers "F.Cu" "F.Mask" "F.Paste")
			(net "PVNN_PCH_STBY")
		)
		(pad "AC36" smd circle
			(at -0.40005 -3.44805 180)
			(size 0.381 0.381)
			(layers "F.Cu" "F.Mask" "F.Paste")
			(net "PVNN_PCH_STBY")
		)
		(pad "AC37" smd circle
			(at 0.40005 -3.44805 180)
			(size 0.381 0.381)
			(layers "F.Cu" "F.Mask" "F.Paste")
			(net "PVNN_PCH_STBY")
		)
		(pad "AC39" smd circle
			(at 1.20015 -3.44805 180)
			(size 0.381 0.381)
			(layers "F.Cu" "F.Mask" "F.Paste")
			(net "PVNN_PCH_STBY")
		)
		(pad "AC41" smd circle
			(at 2.00025 -3.44805 180)
			(size 0.381 0.381)
			(layers "F.Cu" "F.Mask" "F.Paste")
			(net "PVNN_PCH_STBY")
		)
		(pad "AC43" smd circle
			(at 2.80035 -3.44805 180)
			(size 0.381 0.381)
			(layers "F.Cu" "F.Mask" "F.Paste")
			(net "GND")
		)
		(pad "AC45" smd circle
			(at 3.60045 -3.44805 180)
			(size 0.381 0.381)
			(layers "F.Cu" "F.Mask" "F.Paste")
			(net "GND")
		)
		(pad "AC46" smd circle
			(at 4.40055 -3.44805 180)
			(size 0.381 0.381)
			(layers "F.Cu" "F.Mask" "F.Paste")
			(net "GND")
		)
		(pad "AC48" smd circle
			(at 5.20065 -3.44805 180)
			(size 0.381 0.381)
			(layers "F.Cu" "F.Mask" "F.Paste")
			(net "GND")
		)
		(pad "AC52" smd circle
			(at 6.86816 -3.71475)
			(size 0.381 0.381)
			(layers "F.Cu" "F.Mask" "F.Paste")
			(net "GND")
		)
		(pad "AC56" smd circle
			(at 8.5852 -3.71475)
			(size 0.381 0.381)
			(layers "F.Cu" "F.Mask" "F.Paste")
			(net "TP_PCH_RSVD1")
		)
		(pad "AC59" smd circle
			(at 10.30224 -3.71475)
			(size 0.381 0.381)
			(layers "F.Cu" "F.Mask" "F.Paste")
			(net "GND")
		)
		(pad "AC63" smd circle
			(at 12.01928 -3.71475)
			(size 0.381 0.381)
			(layers "F.Cu" "F.Mask" "F.Paste")
			(net "GND")
		)
		(pad "AC66" smd circle
			(at 13.73632 -3.71475)
			(size 0.381 0.381)
			(layers "F.Cu" "F.Mask" "F.Paste")
			(net "GND")
		)
		(pad "AC69" smd circle
			(at 15.064994 -3.50012)
			(size 0.3048 0.3048)
			(layers "F.Cu" "F.Mask" "F.Paste")
			(net "Net_145")
		)
		(pad "AC71" smd circle
			(at 15.895066 -3.50012)
			(size 0.3048 0.3048)
			(layers "F.Cu" "F.Mask" "F.Paste")
			(net "Net_149")
		)
		(pad "AD1" smd oval
			(at -16.310102 -2.999994 180)
			(size 0.254 0.3302)
			(layers "F.Cu" "F.Mask" "F.Paste")
			(net "FM_CPU_BMC_INIT")
		)
		(pad "AD3" smd circle
			(at -15.48003 -2.999994 180)
			(size 0.3048 0.3048)
			(layers "F.Cu" "F.Mask" "F.Paste")
			(net "RST_PCH_SYSRST_BTN_OUT_N")
		)
		(pad "AD5" smd circle
			(at -14.649958 -2.999994 180)
			(size 0.3048 0.3048)
			(layers "F.Cu" "F.Mask" "F.Paste")
			(net "GND")
		)
		(pad "AD9" smd circle
			(at -12.8778 -3.21945)
			(size 0.381 0.381)
			(layers "F.Cu" "F.Mask" "F.Paste")
			(net "FM_OCP_MEZZB_PRES_1V05_PCH_N")
		)
		(pad "AD13" smd circle
			(at -11.16076 -3.21945)
			(size 0.381 0.381)
			(layers "F.Cu" "F.Mask" "F.Paste")
			(net "H_CPU0_MEMDEF_MEMHOT_PCH_N")
		)
		(pad "AD17" smd circle
			(at -9.44372 -3.21945)
			(size 0.381 0.381)
			(layers "F.Cu" "F.Mask" "F.Paste")
			(net "FM_OCP_MEZZC_PRES_1V05_PCH_N")
		)
		(pad "AD20" smd circle
			(at -7.72668 -3.21945)
			(size 0.381 0.381)
			(layers "F.Cu" "F.Mask" "F.Paste")
			(net "TP_PCH_GPP_L11")
		)
		(pad "AD24" smd circle
			(at -6.00964 -3.21945)
			(size 0.381 0.381)
			(layers "F.Cu" "F.Mask" "F.Paste")
			(net "P3V3_STBY")
		)
		(pad "AD50" smd circle
			(at 6.00964 -3.21945)
			(size 0.381 0.381)
			(layers "F.Cu" "F.Mask" "F.Paste")
			(net "P1V05_PCH_STBY_VCCA_XTAL")
		)
		(pad "AD54" smd circle
			(at 7.72668 -3.21945)
			(size 0.381 0.381)
			(layers "F.Cu" "F.Mask" "F.Paste")
			(net "XDP_PRDY_N")
		)
		(pad "AD58" smd circle
			(at 9.44372 -3.21945)
			(size 0.381 0.381)
			(layers "F.Cu" "F.Mask" "F.Paste")
			(net "GND")
		)
		(pad "AD61" smd circle
			(at 11.16076 -3.21945)
			(size 0.381 0.381)
			(layers "F.Cu" "F.Mask" "F.Paste")
			(net "SATA6G_PCH_PCIE_UP_SATA_RXP<7>")
		)
		(pad "AD65" smd circle
			(at 12.8778 -3.21945)
			(size 0.381 0.381)
			(layers "F.Cu" "F.Mask" "F.Paste")
			(net "GND")
		)
		(pad "AD68" smd circle
			(at 14.649958 -2.999994)
			(size 0.3048 0.3048)
			(layers "F.Cu" "F.Mask" "F.Paste")
			(net "GND")
		)
		(pad "AD70" smd circle
			(at 15.48003 -2.999994)
			(size 0.3048 0.3048)
			(layers "F.Cu" "F.Mask" "F.Paste")
			(net "Net_144")
		)
		(pad "AD72" smd oval
			(at 16.310102 -2.999994 180)
			(size 0.254 0.3302)
			(layers "F.Cu" "F.Mask" "F.Paste")
			(net "Net_148")
		)
		(pad "AE2" smd circle
			(at -15.895066 -2.500122 180)
			(size 0.3048 0.3048)
			(layers "F.Cu" "F.Mask" "F.Paste")
			(net "FM_OCP_MEZZA_PRES_R")
		)
		(pad "AE4" smd circle
			(at -15.064994 -2.500122 180)
			(size 0.3048 0.3048)
			(layers "F.Cu" "F.Mask" "F.Paste")
			(net "FM_TPM_PRES_N")
		)
		(pad "AE7" smd circle
			(at -13.73632 -2.72415)
			(size 0.381 0.381)
			(layers "F.Cu" "F.Mask" "F.Paste")
			(net "FM_CPU_ERR0_PCH_N")
		)
		(pad "AE11" smd circle
			(at -12.01928 -2.72415)
			(size 0.381 0.381)
			(layers "F.Cu" "F.Mask" "F.Paste")
			(net "FM_PRSNT_2_3_N")
		)
	)
)
